(kicad_pcb
	(version 20241229)
	(generator "pcbnew")
	(generator_version "9.0")
	(general
		(thickness 1.294)
		(legacy_teardrops no)
	)
	(paper "A3")
	(title_block
		(title "Kintex 410T devboard")
		(date "2024-04-03")
		(rev "1.1.2")
		(comment 9 "footprints 77-82 of 975")
	)
	(layers
		(0 "F.Cu" mixed)
		(4 "In1.Cu" power)
		(6 "In2.Cu" power)
		(8 "In3.Cu" mixed)
		(10 "In4.Cu" power)
		(12 "In5.Cu" mixed)
		(14 "In6.Cu" power)
		(16 "In7.Cu" mixed)
		(18 "In8.Cu" power)
		(2 "B.Cu" mixed)
		(9 "F.Adhes" user "F.Adhesive")
		(11 "B.Adhes" user "B.Adhesive")
		(13 "F.Paste" user)
		(15 "B.Paste" user)
		(5 "F.SilkS" user "F.Silkscreen")
		(7 "B.SilkS" user "B.Silkscreen")
		(1 "F.Mask" user)
		(3 "B.Mask" user)
		(17 "Dwgs.User" user "User.Drawings")
		(19 "Cmts.User" user "User.Comments")
		(21 "Eco1.User" user "User.Eco1")
		(23 "Eco2.User" user "User.Eco2")
		(25 "Edge.Cuts" user)
		(27 "Margin" user)
		(31 "F.CrtYd" user "F.Courtyard")
		(29 "B.CrtYd" user "B.Courtyard")
		(35 "F.Fab" user)
		(33 "B.Fab" user)
	)
	(footprint "antmicro-footprints:USB-A_Receptacle_WE_614004184726"
		(layer "F.Cu")
		(at 262.375 104.1 90)
		(descr "USB-A (USB TYPE-A) USB 2.0 Receptacle Connector 4 Position Through Hole, Right Angle")
		(property "Reference" "J12"
			(at 5.55 -1.375 180)
			(layer "F.SilkS")
			(effects
				(font
					(size 0.7 0.7)
					(thickness 0.15)
				)
				(justify left bottom)
			)
		)
		(property "Value" "USB-A_WE_614004184726"
			(at 3.7 8.2 180)
			(layer "F.Fab")
			(effects
				(font
					(size 0.7 0.7)
					(thickness 0.15)
				)
				(justify left bottom)
			)
		)
		(property "Description" "USB-A (USB TYPE-A) USB 2.0 Receptacle Connector 4 Position Through Hole, Right Angle"
			(at 0 0 90)
			(layer "F.Fab")
			(hide yes)
			(effects
				(font
					(size 1.27 1.27)
					(thickness 0.15)
				)
			)
		)
		(property "Author" "Antmicro"
			(at 366.475 -158.275 0)
			(layer "F.Fab")
			(hide yes)
			(effects
				(font
					(size 1 1)
					(thickness 0.15)
				)
			)
		)
		(property "License" "Apache-2.0"
			(at 366.475 -158.275 0)
			(layer "F.Fab")
			(hide yes)
			(effects
				(font
					(size 1 1)
					(thickness 0.15)
				)
			)
		)
		(property "MPN" "614004184726"
			(at 366.475 -158.275 0)
			(layer "F.Fab")
			(hide yes)
			(effects
				(font
					(size 1 1)
					(thickness 0.15)
				)
			)
		)
		(property "Manufacturer" "Würth Elektronik"
			(at 366.475 -158.275 0)
			(layer "F.Fab")
			(hide yes)
			(effects
				(font
					(size 1 1)
					(thickness 0.15)
				)
			)
		)
		(sheetname "USB PHY")
		(sheetfile "usb-phy.kicad_sch")
		(attr through_hole)
		(fp_line
			(start 5.31 -1.25)
			(end 5.31 0.498)
			(stroke
				(width 0.15)
				(type solid)
			)
			(layer "F.SilkS")
		)
		(fp_line
			(start -1.111 -1.25)
			(end 5.31 -1.25)
			(stroke
				(width 0.15)
				(type solid)
			)
			(layer "F.SilkS")
		)
		(fp_line
			(start -1.111 0.498)
			(end -1.111 -1.25)
			(stroke
				(width 0.15)
				(type solid)
			)
			(layer "F.SilkS")
		)
		(fp_line
			(start -1.111 4.498)
			(end -1.111 9.499)
			(stroke
				(width 0.15)
				(type solid)
			)
			(layer "F.SilkS")
		)
		(fp_line
			(start 5.31 9.499)
			(end 5.31 4.498)
			(stroke
				(width 0.15)
				(type solid)
			)
			(layer "F.SilkS")
		)
		(fp_line
			(start -1.111 9.499)
			(end 5.31 9.499)
			(stroke
				(width 0.15)
				(type solid)
			)
			(layer "F.SilkS")
		)
		(fp_circle
			(center -0.45 -1.527)
			(end -0.4 -1.527)
			(stroke
				(width 0.15)
				(type solid)
			)
			(fill yes)
			(layer "F.SilkS")
		)
		(fp_rect
			(start -1.55 -1.577)
			(end 5.76 10.425)
			(stroke
				(width 0.05)
				(type solid)
			)
			(fill no)
			(layer "F.CrtYd")
		)
		(fp_line
			(start 5.31 -1.25)
			(end -1.111 -1.25)
			(stroke
				(width 0.15)
				(type solid)
			)
			(layer "F.Fab")
		)
		(fp_line
			(start -1.111 -1.25)
			(end -1.111 9.499)
			(stroke
				(width 0.15)
				(type solid)
			)
			(layer "F.Fab")
		)
		(fp_line
			(start -1.121 -1.01)
			(end -0.88 -1.25)
			(stroke
				(width 0.15)
				(type solid)
			)
			(layer "F.Fab")
		)
		(fp_line
			(start 5.31 9.499)
			(end 5.31 -1.25)
			(stroke
				(width 0.15)
				(type solid)
			)
			(layer "F.Fab")
		)
		(fp_line
			(start -1.111 9.499)
			(end 5.31 9.499)
			(stroke
				(width 0.15)
				(type solid)
			)
			(layer "F.Fab")
		)
		(pad "1" thru_hole circle
			(at 0 0 90)
			(size 1.25 1.25)
			(drill 0.92)
			(layers "*.Cu" "*.Mask")
			(remove_unused_layers no)
			(net 705 "/USB PHY/USB_HOST_VBUS")
			(pinfunction "VBUS")
			(pintype "passive")
		)
		(pad "2" thru_hole circle
			(at 1.4 0 90)
			(size 1.25 1.25)
			(drill 0.92)
			(layers "*.Cu" "*.Mask")
			(remove_unused_layers no)
			(net 835 "/USB PHY/USB_HOST_CONN_D-")
			(pinfunction "D-")
			(pintype "bidirectional")
		)
		(pad "3" thru_hole circle
			(at 2.798 0 90)
			(size 1.25 1.25)
			(drill 0.92)
			(layers "*.Cu" "*.Mask")
			(remove_unused_layers no)
			(net 836 "/USB PHY/USB_HOST_CONN_D+")
			(pinfunction "D+")
			(pintype "bidirectional")
		)
		(pad "4" thru_hole circle
			(at 4.2 0 90)
			(size 1.25 1.25)
			(drill 0.92)
			(layers "*.Cu" "*.Mask")
			(remove_unused_layers no)
			(net 1 "GND")
			(pinfunction "GND")
			(pintype "power_in")
		)
		(pad "SH" thru_hole roundrect
			(at -0.651 2.499 90)
			(size 1.8 3.3)
			(drill oval 1.2 2.5)
			(layers "*.Cu" "*.Mask")
			(remove_unused_layers no)
			(roundrect_rratio 0.25)
			(net 1 "GND")
			(pinfunction "SH")
			(pintype "passive")
		)
		(pad "SH" thru_hole roundrect
			(at 2.1 5.599 90)
			(size 1.5 2)
			(drill oval 1 1.5)
			(layers "*.Cu" "*.Mask")
			(remove_unused_layers no)
			(roundrect_rratio 0.25)
			(net 1 "GND")
			(pinfunction "SH")
			(pintype "passive")
		)
		(pad "SH" thru_hole roundrect
			(at 4.849 2.499 90)
			(size 1.8 3.3)
			(drill oval 1.2 2.5)
			(layers "*.Cu" "*.Mask")
			(remove_unused_layers no)
			(roundrect_rratio 0.25)
			(net 1 "GND")
			(pinfunction "SH")
			(pintype "passive")
		)
	)
	(footprint "antmicro-footprints:R_0402_1005Metric"
		(layer "F.Cu")
		(at 250.399 99.5 90)
		(descr "Resistor SMD 0402")
		(tags "resistor SMD 0402")
		(property "Reference" "R346"
			(at -3 -0.449 90)
			(layer "F.SilkS")
			(effects
				(font
					(size 0.7 0.7)
					(thickness 0.15)
				)
				(justify left bottom)
			)
		)
		(property "Value" "R_12k_0402"
			(at 0 1.4 90)
			(layer "F.Fab")
			(effects
				(font
					(size 0.7 0.7)
					(thickness 0.15)
				)
				(justify left bottom)
			)
		)
		(property "Description" "SMD Chip Resistor, 12 kohm, ± 1%, 62.5 mW, 0402 [1005 Metric], Thick Film, General Purpose"
			(at 0 0 90)
			(layer "F.Fab")
			(hide yes)
			(effects
				(font
					(size 1.27 1.27)
					(thickness 0.15)
				)
			)
		)
		(property "Author" "Antmicro"
			(at 349.899 -150.899 0)
			(layer "F.Fab")
			(hide yes)
			(effects
				(font
					(size 1 1)
					(thickness 0.15)
				)
			)
		)
		(property "License" "Apache-2.0"
			(at 349.899 -150.899 0)
			(layer "F.Fab")
			(hide yes)
			(effects
				(font
					(size 1 1)
					(thickness 0.15)
				)
			)
		)
		(property "MPN" "CR0402-FX-1202GLF"
			(at 349.899 -150.899 0)
			(layer "F.Fab")
			(hide yes)
			(effects
				(font
					(size 1 1)
					(thickness 0.15)
				)
			)
		)
		(property "Manufacturer" "Bourns"
			(at 349.899 -150.899 0)
			(layer "F.Fab")
			(hide yes)
			(effects
				(font
					(size 1 1)
					(thickness 0.15)
				)
			)
		)
		(property "Tolerance" "1%"
			(at 349.899 -150.899 0)
			(layer "F.Fab")
			(hide yes)
			(effects
				(font
					(size 1 1)
					(thickness 0.15)
				)
			)
		)
		(property "Val" "12k"
			(at 349.899 -150.899 0)
			(layer "F.Fab")
			(hide yes)
			(effects
				(font
					(size 1 1)
					(thickness 0.15)
				)
			)
		)
		(sheetname "USB PHY")
		(sheetfile "usb-phy.kicad_sch")
		(attr smd)
		(fp_rect
			(start -0.925 -0.47)
			(end 0.925 0.47)
			(stroke
				(width 0.05)
				(type default)
			)
			(fill no)
			(layer "F.CrtYd")
		)
		(fp_rect
			(start -0.5 -0.25)
			(end 0.5 0.25)
			(stroke
				(width 0.15)
				(type solid)
			)
			(fill no)
			(layer "F.Fab")
		)
		(pad "1" smd roundrect
			(at -0.48 0 90)
			(size 0.59 0.64)
			(layers "F.Cu" "F.Mask" "F.Paste")
			(roundrect_rratio 0.25)
			(net 1 "GND")
			(pintype "passive")
		)
		(pad "2" smd roundrect
			(at 0.48 0 90)
			(size 0.59 0.64)
			(layers "F.Cu" "F.Mask" "F.Paste")
			(roundrect_rratio 0.25)
			(net 382 "Net-(U30-ISET)")
			(pintype "passive")
		)
	)
	(footprint "antmicro-footprints:R_0402_1005Metric"
		(layer "F.Cu")
		(at 213.9 154.71 -90)
		(descr "Resistor SMD 0402")
		(tags "resistor SMD 0402")
		(property "Reference" "R81"
			(at -0.96 0.4 270)
			(layer "F.SilkS")
			(effects
				(font
					(size 0.7 0.7)
					(thickness 0.15)
				)
				(justify left bottom)
			)
		)
		(property "Value" "R_0R_0402"
			(at 0 1.4 270)
			(layer "F.Fab")
			(effects
				(font
					(size 0.7 0.7)
					(thickness 0.15)
				)
				(justify left bottom)
			)
		)
		(property "Description" "SMD Chip Resistor, Jumper, 0 ohm, 100 mW, 0402 [1005 Metric], Thick Film, General Purpose"
			(at 0 0 270)
			(layer "F.Fab")
			(hide yes)
			(effects
				(font
					(size 1.27 1.27)
					(thickness 0.15)
				)
			)
		)
		(property "Author" "Antmicro"
			(at 59.19 368.61 0)
			(layer "F.Fab")
			(hide yes)
			(effects
				(font
					(size 1 1)
					(thickness 0.15)
				)
			)
		)
		(property "Current" "1A"
			(at 59.19 368.61 0)
			(layer "F.Fab")
			(hide yes)
			(effects
				(font
					(size 1 1)
					(thickness 0.15)
				)
			)
		)
		(property "License" "Apache-2.0"
			(at 59.19 368.61 0)
			(layer "F.Fab")
			(hide yes)
			(effects
				(font
					(size 1 1)
					(thickness 0.15)
				)
			)
		)
		(property "MPN" "ERJ2GE0R00X"
			(at 59.19 368.61 0)
			(layer "F.Fab")
			(hide yes)
			(effects
				(font
					(size 1 1)
					(thickness 0.15)
				)
			)
		)
		(property "Manufacturer" "Panasonic"
			(at 59.19 368.61 0)
			(layer "F.Fab")
			(hide yes)
			(effects
				(font
					(size 1 1)
					(thickness 0.15)
				)
			)
		)
		(property "Tolerance" ""
			(at 59.19 368.61 0)
			(layer "F.Fab")
			(hide yes)
			(effects
				(font
					(size 1 1)
					(thickness 0.15)
				)
			)
		)
		(property "Val" "0R"
			(at 59.19 368.61 0)
			(layer "F.Fab")
			(hide yes)
			(effects
				(font
					(size 1 1)
					(thickness 0.15)
				)
			)
		)
		(sheetname "SPI Flash + SD Card")
		(sheetfile "spi-flash.kicad_sch")
		(attr smd)
		(fp_rect
			(start -0.925 -0.47)
			(end 0.925 0.47)
			(stroke
				(width 0.05)
				(type default)
			)
			(fill no)
			(layer "F.CrtYd")
		)
		(fp_rect
			(start -0.5 -0.25)
			(end 0.5 0.25)
			(stroke
				(width 0.15)
				(type solid)
			)
			(fill no)
			(layer "F.Fab")
		)
		(pad "1" smd roundrect
			(at -0.48 0 270)
			(size 0.59 0.64)
			(layers "F.Cu" "F.Mask" "F.Paste")
			(roundrect_rratio 0.25)
			(net 408 "/FPGA Bank 33 & 34/USR_FLASH_0.CLK")
			(pintype "passive")
		)
		(pad "2" smd roundrect
			(at 0.48 0 270)
			(size 0.59 0.64)
			(layers "F.Cu" "F.Mask" "F.Paste")
			(roundrect_rratio 0.25)
			(net 901 "/SPI Flash + SD Card/USR_FLASH_0_CLK")
			(pintype "passive")
		)
	)
	(footprint "antmicro-footprints:C_0402_1005Metric"
		(layer "F.Cu")
		(at 233.7 150.9)
		(descr "Capacitor SMD 0402")
		(tags "capacitor SMD 0402")
		(property "Reference" "C246"
			(at -1.85 1.2 0)
			(layer "F.SilkS")
			(effects
				(font
					(size 0.7 0.7)
					(thickness 0.15)
				)
				(justify left bottom)
			)
		)
		(property "Value" "C_100n_0402"
			(at 0 1.169 0)
			(layer "F.Fab")
			(effects
				(font
					(size 0.7 0.7)
					(thickness 0.15)
				)
				(justify left bottom)
			)
		)
		(property "Description" "SMD Multilayer Ceramic Capacitor, 0.1 µF, 50 V, 0402 [1005 Metric], ± 10%, X5R, GRM Series"
			(at 0 0 0)
			(layer "F.Fab")
			(hide yes)
			(effects
				(font
					(size 1.27 1.27)
					(thickness 0.15)
				)
			)
		)
		(property "Author" "Antmicro"
			(at 0 0 0)
			(layer "F.Fab")
			(hide yes)
			(effects
				(font
					(size 1 1)
					(thickness 0.15)
				)
			)
		)
		(property "Dielectric" "X5R"
			(at 0 0 0)
			(layer "F.Fab")
			(hide yes)
			(effects
				(font
					(size 1 1)
					(thickness 0.15)
				)
			)
		)
		(property "License" "Apache-2.0"
			(at 0 0 0)
			(layer "F.Fab")
			(hide yes)
			(effects
				(font
					(size 1 1)
					(thickness 0.15)
				)
			)
		)
		(property "MPN" "GRM155R61H104KE14D"
			(at 0 0 0)
			(layer "F.Fab")
			(hide yes)
			(effects
				(font
					(size 1 1)
					(thickness 0.15)
				)
			)
		)
		(property "Manufacturer" "Murata"
			(at 0 0 0)
			(layer "F.Fab")
			(hide yes)
			(effects
				(font
					(size 1 1)
					(thickness 0.15)
				)
			)
		)
		(property "Val" "100n"
			(at 0 0 0)
			(layer "F.Fab")
			(hide yes)
			(effects
				(font
					(size 1 1)
					(thickness 0.15)
				)
			)
		)
		(property "Voltage" "50V"
			(at 0 0 0)
			(layer "F.Fab")
			(hide yes)
			(effects
				(font
					(size 1 1)
					(thickness 0.15)
				)
			)
		)
		(sheetname "USB PHY")
		(sheetfile "usb-phy.kicad_sch")
		(attr smd)
		(fp_rect
			(start -0.925 -0.47)
			(end 0.925 0.47)
			(stroke
				(width 0.05)
				(type default)
			)
			(fill no)
			(layer "F.CrtYd")
		)
		(fp_line
			(start -0.494 -0.25)
			(end 0.504 -0.25)
			(stroke
				(width 0.15)
				(type solid)
			)
			(layer "F.Fab")
		)
		(fp_line
			(start -0.494 0.248)
			(end -0.494 -0.25)
			(stroke
				(width 0.15)
				(type solid)
			)
			(layer "F.Fab")
		)
		(fp_line
			(start 0.504 -0.25)
			(end 0.504 0.248)
			(stroke
				(width 0.15)
				(type solid)
			)
			(layer "F.Fab")
		)
		(fp_line
			(start 0.504 0.248)
			(end -0.494 0.248)
			(stroke
				(width 0.15)
				(type solid)
			)
			(layer "F.Fab")
		)
		(pad "1" smd roundrect
			(at -0.48 0)
			(size 0.59 0.64)
			(layers "F.Cu" "F.Mask" "F.Paste")
			(roundrect_rratio 0.25)
			(net 1 "GND")
			(pintype "passive")
		)
		(pad "2" smd roundrect
			(at 0.48 0)
			(size 0.59 0.64)
			(layers "F.Cu" "F.Mask" "F.Paste")
			(roundrect_rratio 0.25)
			(net 26 "+1V8")
			(pintype "passive")
		)
	)
	(footprint "antmicro-footprints:C_0402_1005Metric"
		(layer "F.Cu")
		(at 198.951 104.199 -90)
		(descr "Capacitor SMD 0402")
		(tags "capacitor SMD 0402")
		(property "Reference" "C220"
			(at -3.599 -0.349 270)
			(layer "F.SilkS")
			(effects
				(font
					(size 0.7 0.7)
					(thickness 0.15)
				)
				(justify right bottom)
			)
		)
		(property "Value" "C_22p_0402"
			(at 0 1.4 90)
			(layer "F.Fab")
			(effects
				(font
					(size 0.7 0.7)
					(thickness 0.15)
				)
				(justify right bottom)
			)
		)
		(property "Description" "SMD Multilayer Ceramic Capacitor, 22 pF, 50 V, 0402 [1005 Metric], ± 5%, C0G / NP0, CC Series"
			(at 0 0 270)
			(layer "F.Fab")
			(hide yes)
			(effects
				(font
					(size 1.27 1.27)
					(thickness 0.15)
				)
			)
		)
		(property "Author" "Antmicro"
			(at 94.752 303.15 0)
			(layer "F.Fab")
			(hide yes)
			(effects
				(font
					(size 1 1)
					(thickness 0.15)
				)
			)
		)
		(property "Dielectric" ""
			(at 94.752 303.15 0)
			(layer "F.Fab")
			(hide yes)
			(effects
				(font
					(size 1 1)
					(thickness 0.15)
				)
			)
		)
		(property "License" "Apache-2.0"
			(at 94.752 303.15 0)
			(layer "F.Fab")
			(hide yes)
			(effects
				(font
					(size 1 1)
					(thickness 0.15)
				)
			)
		)
		(property "MPN" "CC0402JRNPO9BN220"
			(at 94.752 303.15 0)
			(layer "F.Fab")
			(hide yes)
			(effects
				(font
					(size 1 1)
					(thickness 0.15)
				)
			)
		)
		(property "Manufacturer" "YAGEO"
			(at 94.752 303.15 0)
			(layer "F.Fab")
			(hide yes)
			(effects
				(font
					(size 1 1)
					(thickness 0.15)
				)
			)
		)
		(property "Val" "22p"
			(at 94.752 303.15 0)
			(layer "F.Fab")
			(hide yes)
			(effects
				(font
					(size 1 1)
					(thickness 0.15)
				)
			)
		)
		(property "Voltage" ""
			(at 94.752 303.15 0)
			(layer "F.Fab")
			(hide yes)
			(effects
				(font
					(size 1 1)
					(thickness 0.15)
				)
			)
		)
		(sheetname "USB PHY")
		(sheetfile "usb-phy.kicad_sch")
		(attr smd)
		(fp_rect
			(start -0.925 -0.47)
			(end 0.925 0.47)
			(stroke
				(width 0.05)
				(type default)
			)
			(fill no)
			(layer "F.CrtYd")
		)
		(fp_line
			(start -0.494 0.248)
			(end -0.494 -0.25)
			(stroke
				(width 0.15)
				(type solid)
			)
			(layer "F.Fab")
		)
		(fp_line
			(start 0.504 0.248)
			(end -0.494 0.248)
			(stroke
				(width 0.15)
				(type solid)
			)
			(layer "F.Fab")
		)
		(fp_line
			(start -0.494 -0.25)
			(end 0.504 -0.25)
			(stroke
				(width 0.15)
				(type solid)
			)
			(layer "F.Fab")
		)
		(fp_line
			(start 0.504 -0.25)
			(end 0.504 0.248)
			(stroke
				(width 0.15)
				(type solid)
			)
			(layer "F.Fab")
		)
		(pad "1" smd roundrect
			(at -0.48 0 270)
			(size 0.59 0.64)
			(layers "F.Cu" "F.Mask" "F.Paste")
			(roundrect_rratio 0.25)
			(net 1 "GND")
			(pintype "passive")
		)
		(pad "2" smd roundrect
			(at 0.48 0 270)
			(size 0.59 0.64)
			(layers "F.Cu" "F.Mask" "F.Paste")
			(roundrect_rratio 0.25)
			(net 706 "/USB PHY/USB_HOST_XI")
			(pintype "passive")
		)
	)
	(footprint "antmicro-footprints:C_0402_1005Metric"
		(layer "F.Cu")
		(at 254.445 137.935 180)
		(descr "Capacitor SMD 0402")
		(tags "capacitor SMD 0402")
		(property "Reference" "C239"
			(at 1.4 4.9 180)
			(layer "F.SilkS")
			(effects
				(font
					(size 0.7 0.7)
					(thickness 0.15)
				)
				(justify left bottom)
			)
		)
		(property "Value" "C_100n_0402"
			(at 0 1.169 180)
			(layer "F.Fab")
			(effects
				(font
					(size 0.7 0.7)
					(thickness 0.15)
				)
				(justify left bottom)
			)
		)
		(property "Description" "SMD Multilayer Ceramic Capacitor, 0.1 µF, 50 V, 0402 [1005 Metric], ± 10%, X5R, GRM Series"
			(at 0 0 180)
			(layer "F.Fab")
			(hide yes)
			(effects
				(font
					(size 1.27 1.27)
					(thickness 0.15)
				)
			)
		)
		(property "Author" "Antmicro"
			(at 508.89 275.87 0)
			(layer "F.Fab")
			(hide yes)
			(effects
				(font
					(size 1 1)
					(thickness 0.15)
				)
			)
		)
		(property "Dielectric" "X5R"
			(at 508.89 275.87 0)
			(layer "F.Fab")
			(hide yes)
			(effects
				(font
					(size 1 1)
					(thickness 0.15)
				)
			)
		)
		(property "License" "Apache-2.0"
			(at 508.89 275.87 0)
			(layer "F.Fab")
			(hide yes)
			(effects
				(font
					(size 1 1)
					(thickness 0.15)
				)
			)
		)
		(property "MPN" "GRM155R61H104KE14D"
			(at 508.89 275.87 0)
			(layer "F.Fab")
			(hide yes)
			(effects
				(font
					(size 1 1)
					(thickness 0.15)
				)
			)
		)
		(property "Manufacturer" "Murata"
			(at 508.89 275.87 0)
			(layer "F.Fab")
			(hide yes)
			(effects
				(font
					(size 1 1)
					(thickness 0.15)
				)
			)
		)
		(property "Val" "100n"
			(at 508.89 275.87 0)
			(layer "F.Fab")
			(hide yes)
			(effects
				(font
					(size 1 1)
					(thickness 0.15)
				)
			)
		)
		(property "Voltage" "50V"
			(at 508.89 275.87 0)
			(layer "F.Fab")
			(hide yes)
			(effects
				(font
					(size 1 1)
					(thickness 0.15)
				)
			)
		)
		(sheetname "USB PHY")
		(sheetfile "usb-phy.kicad_sch")
		(attr smd)
		(fp_rect
			(start -0.925 -0.47)
			(end 0.925 0.47)
			(stroke
				(width 0.05)
				(type default)
			)
			(fill no)
			(layer "F.CrtYd")
		)
		(fp_line
			(start 0.504 0.248)
			(end -0.494 0.248)
			(stroke
				(width 0.15)
				(type solid)
			)
			(layer "F.Fab")
		)
		(fp_line
			(start 0.504 -0.25)
			(end 0.504 0.248)
			(stroke
				(width 0.15)
				(type solid)
			)
			(layer "F.Fab")
		)
		(fp_line
			(start -0.494 0.248)
			(end -0.494 -0.25)
			(stroke
				(width 0.15)
				(type solid)
			)
			(layer "F.Fab")
		)
		(fp_line
			(start -0.494 -0.25)
			(end 0.504 -0.25)
			(stroke
				(width 0.15)
				(type solid)
			)
			(layer "F.Fab")
		)
		(pad "1" smd roundrect
			(at -0.48 0 180)
			(size 0.59 0.64)
			(layers "F.Cu" "F.Mask" "F.Paste")
			(roundrect_rratio 0.25)
			(net 1 "GND")
			(pintype "passive")
		)
		(pad "2" smd roundrect
			(at 0.48 0 180)
			(size 0.59 0.64)
			(layers "F.Cu" "F.Mask" "F.Paste")
			(roundrect_rratio 0.25)
			(net 714 "/USB PHY/FTDI_VPHY")
			(pintype "passive")
		)
	)
)
